(kicad_pcb
	(version 20240108)
	(generator "pcbnew")
	(generator_version "8.0")
	(general
		(thickness 1.62)
		(legacy_teardrops no)
	)
	(paper "A4")
	(title_block
		(title "Jetson Orin Baseboard")
		(date "2025-03-12")
		(rev "1.3.4")
		(company "Antmicro Ltd")
		(comment 1 "www.antmicro.com")
		(comment 9 "footprint 59 of 677 (J15), pads 255-264 of 264")
	)
	(layers
		(0 "F.Cu" signal)
		(1 "In1.Cu" signal)
		(2 "In2.Cu" signal)
		(3 "In3.Cu" signal)
		(4 "In4.Cu" jumper)
		(5 "In5.Cu" signal)
		(6 "In6.Cu" signal)
		(31 "B.Cu" signal)
		(32 "B.Adhes" user "B.Adhesive")
		(33 "F.Adhes" user "F.Adhesive")
		(34 "B.Paste" user)
		(35 "F.Paste" user)
		(36 "B.SilkS" user "B.Silkscreen")
		(37 "F.SilkS" user "F.Silkscreen")
		(38 "B.Mask" user)
		(39 "F.Mask" user)
		(40 "Dwgs.User" user "User.Drawings")
		(41 "Cmts.User" user "User.Comments")
		(42 "Eco1.User" user "User.Eco1")
		(43 "Eco2.User" user "User.Eco2")
		(44 "Edge.Cuts" user)
		(45 "Margin" user)
		(46 "B.CrtYd" user "B.Courtyard")
		(47 "F.CrtYd" user "F.Courtyard")
		(48 "B.Fab" user)
		(49 "F.Fab" user)
	)
	(footprint "antmicro-footprints:TE_2309413"
		(locked yes)
		(layer "F.Cu")
		(at 92.706 84.0225)
		(descr "260 pin DDR4 SODIMM Right Angle Socket, 9.2 mm (0.362 in) Stack Height, https://www.te.com/global-en/product-2309413-1.html")
		(tags "ddr4 sodimm right angle 9.2mm height jetson som")
		(property "Reference" "J15"
			(at -36.75 -13.25 0)
			(layer "F.SilkS")
			(effects
				(font
					(size 0.7 0.7)
					(thickness 0.15)
				)
				(justify left bottom)
			)
		)
		(property "Value" "Bus_DDR4_SODIMM_CUSTOM_Jetson-Orin-H9.2mm-socket"
			(at -38 14.25 0)
			(layer "F.Fab")
			(effects
				(font
					(size 0.7 0.7)
					(thickness 0.15)
				)
				(justify left bottom)
			)
		)
		(property "Footprint" "antmicro-footprints:TE_2309413"
			(at 0 0 0)
			(layer "F.Fab")
			(hide yes)
			(effects
				(font
					(size 1.27 1.27)
					(thickness 0.15)
				)
			)
		)
		(property "Datasheet" "https://developer.nvidia.com/jetson-orin-nx-series-data-sheet"
			(at 0 0 0)
			(layer "F.Fab")
			(hide yes)
			(effects
				(font
					(size 1.27 1.27)
					(thickness 0.15)
				)
			)
		)
		(property "Author" "Antmicro"
			(at 0 0 0)
			(layer "F.Fab")
			(hide yes)
			(effects
				(font
					(size 1 1)
					(thickness 0.15)
				)
			)
		)
		(property "License" "Apache-2.0"
			(at 0 0 0)
			(layer "F.Fab")
			(hide yes)
			(effects
				(font
					(size 1 1)
					(thickness 0.15)
				)
			)
		)
		(property "MPN" "2309413-1"
			(at 0 0 0)
			(layer "F.Fab")
			(hide yes)
			(effects
				(font
					(size 1 1)
					(thickness 0.15)
				)
			)
		)
		(property "Manufacturer" "TE Connectivity"
			(at 0 0 0)
			(layer "F.Fab")
			(hide yes)
			(effects
				(font
					(size 1 1)
					(thickness 0.15)
				)
			)
		)
		(sheetname "SoM")
		(sheetfile "som.kicad_sch")
		(attr smd)
		(pad "253" smd rect
			(at -31.63 -12.026 90)
			(size 1.75 0.3)
			(layers "F.Cu" "F.Paste" "F.Mask")
			(net 438 "/SoM/SoM_VIN")
			(pinfunction "VDD_IN")
			(pintype "passive")
		)
		(pad "254" smd rect
			(at -31.88 -3.826 90)
			(size 1.75 0.3)
			(layers "F.Cu" "F.Paste" "F.Mask")
			(net 438 "/SoM/SoM_VIN")
			(pinfunction "VDD_IN")
			(pintype "passive")
		)
		(pad "255" smd rect
			(at -32.131 -12.026 90)
			(size 1.75 0.3)
			(layers "F.Cu" "F.Paste" "F.Mask")
			(net 438 "/SoM/SoM_VIN")
			(pinfunction "VDD_IN")
			(pintype "passive")
		)
		(pad "256" smd rect
			(at -32.381 -3.826 90)
			(size 1.75 0.3)
			(layers "F.Cu" "F.Paste" "F.Mask")
			(net 438 "/SoM/SoM_VIN")
			(pinfunction "VDD_IN")
			(pintype "passive")
		)
		(pad "257" smd rect
			(at -32.631 -12.026 90)
			(size 1.75 0.3)
			(layers "F.Cu" "F.Paste" "F.Mask")
			(net 438 "/SoM/SoM_VIN")
			(pinfunction "VDD_IN")
			(pintype "passive")
		)
		(pad "258" smd rect
			(at -32.881 -3.826 90)
			(size 1.75 0.3)
			(layers "F.Cu" "F.Paste" "F.Mask")
			(net 438 "/SoM/SoM_VIN")
			(pinfunction "VDD_IN")
			(pintype "passive")
		)
		(pad "259" smd rect
			(at -33.131 -12.026 90)
			(size 1.75 0.3)
			(layers "F.Cu" "F.Paste" "F.Mask")
			(net 438 "/SoM/SoM_VIN")
			(pinfunction "VDD_IN")
			(pintype "passive")
		)
		(pad "260" smd rect
			(at -33.381 -3.826 90)
			(size 1.75 0.3)
			(layers "F.Cu" "F.Paste" "F.Mask")
			(net 438 "/SoM/SoM_VIN")
			(pinfunction "VDD_IN")
			(pintype "passive")
		)
		(pad "261" smd rect
			(at -37.756 0.073 180)
			(size 2 3.5)
			(layers "F.Cu" "F.Paste" "F.Mask")
			(net 754 "unconnected-(J15A-MP-Pad261)")
			(pinfunction "MP")
			(pintype "passive+no_connect")
		)
		(pad "262" smd rect
			(at 37.744 4.073 180)
			(size 2 3.5)
			(layers "F.Cu" "F.Paste" "F.Mask")
			(net 755 "unconnected-(J15A-MP-Pad262)")
			(pinfunction "MP")
			(pintype "passive+no_connect")
		)
	)
)
